(kicad_pcb
	(version 20260206)
	(generator "pcbnew")
	(generator_version "10.0")
	(general
		(thickness 1.6)
		(legacy_teardrops no)
	)
	(paper "A4")
	(title_block
		(title "Wiwynn_Tioga_Pass_MB.brd")
		(comment 1 "Tioga Pass / footprints 23-29 of 4770")
	)
	(layers
		(0 "F.Cu" signal "TOP")
		(4 "In1.Cu" signal "L2GND")
		(6 "In2.Cu" signal "L3")
		(8 "In3.Cu" signal "L4GND")
		(10 "In4.Cu" signal "L5")
		(12 "In5.Cu" signal "L6GND")
		(14 "In6.Cu" signal "L7VCC")
		(16 "In7.Cu" signal "L8VCC")
		(18 "In8.Cu" signal "L9GND")
		(20 "In9.Cu" signal "L10")
		(22 "In10.Cu" signal "L11GND")
		(24 "In11.Cu" signal "L12")
		(26 "In12.Cu" signal "L13GND")
		(2 "B.Cu" signal "BOTTOM")
		(9 "F.Adhes" user "F.Adhesive")
		(11 "B.Adhes" user "B.Adhesive")
		(13 "F.Paste" user "Package Geometry/Pastemask Top")
		(15 "B.Paste" user "Package Geometry/Pastemask Bottom")
		(5 "F.SilkS" user "Ref Des/Silkscreen Top")
		(7 "B.SilkS" user "Ref Des/Silkscreen Bottom")
		(1 "F.Mask" user "Board Geometry/Soldermask Top")
		(3 "B.Mask" user "Board Geometry/Soldermask Bottom")
		(17 "Dwgs.User" user "User.Drawings")
		(19 "Cmts.User" user "User.Comments")
		(21 "Eco1.User" user "User.Eco1")
		(23 "Eco2.User" user "User.Eco2")
		(25 "Edge.Cuts" user "Board Geometry/Outline")
		(27 "Margin" user)
		(31 "F.CrtYd" user "Package Geometry/Place Bound Top")
		(29 "B.CrtYd" user "Package Geometry/Place Bound Bottom")
		(35 "F.Fab" user "Ref Des/Assembly Top")
		(33 "B.Fab" user "Ref Des/Assembly Bottom")
	)
	(footprint ""
		(layer "F.Cu")
		(at 27.813 -3.766312)
		(property "Reference" "R1G14"
			(at 0 0 0)
			(layer "F.SilkS")
			(hide yes)
			(effects
				(font
					(size 1.27 1.27)
				)
			)
		)
		(property "Value" ""
			(at 0 0 0)
			(layer "F.Fab")
			(effects
				(font
					(size 1.27 1.27)
				)
			)
		)
		(duplicate_pad_numbers_are_jumpers no)
		(fp_poly
			(pts
				(xy -0.2794 -0.1016) (xy 0.2794 -0.1016) (xy 0.2794 0.9906) (xy -0.2794 0.9906)
			)
			(stroke
				(width 0)
				(type default)
			)
			(fill no)
			(layer "F.CrtYd")
		)
		(fp_line
			(start -0.2794 -0.1016)
			(end -0.2794 0.9906)
			(stroke
				(width 0.1)
				(type default)
			)
			(layer "F.Fab")
		)
		(fp_line
			(start -0.2794 0.9906)
			(end 0.2794 0.9906)
			(stroke
				(width 0.1)
				(type default)
			)
			(layer "F.Fab")
		)
		(fp_line
			(start 0.2794 -0.1016)
			(end -0.2794 -0.1016)
			(stroke
				(width 0.1)
				(type default)
			)
			(layer "F.Fab")
		)
		(fp_line
			(start 0.2794 0.9906)
			(end 0.2794 -0.1016)
			(stroke
				(width 0.1)
				(type default)
			)
			(layer "F.Fab")
		)
		(pad "1" smd rect
			(at 0 0)
			(size 0.508 0.508)
			(layers "F.Cu" "F.Mask" "F.Paste")
			(net "M_J_CPU_VREF")
		)
		(pad "2" smd rect
			(at 0 0.889)
			(size 0.508 0.508)
			(layers "F.Cu" "F.Mask" "F.Paste")
			(net "M_J_VREF")
		)
		(zone
			(layer "F.Cu")
			(hatch none 0.5)
			(connect_pads
				(clearance 0)
			)
			(min_thickness 0.25)
			(keepout
				(tracks allowed)
				(vias not_allowed)
				(pads allowed)
				(copperpour not_allowed)
				(footprints allowed)
			)
			(placement
				(enabled no)
				(sheetname "")
			)
			(fill
				(thermal_gap 0.5)
				(thermal_bridge_width 0.5)
				(island_removal_mode 0)
			)
			(polygon
				(pts
					(xy 27.559 -3.512312) (xy 28.067 -3.512312) (xy 28.067 -3.131312) (xy 27.559 -3.131312)
				)
			)
		)
		(zone
			(layer "F.Cu")
			(hatch none 0.5)
			(connect_pads
				(clearance 0)
			)
			(min_thickness 0.25)
			(keepout
				(tracks not_allowed)
				(vias allowed)
				(pads allowed)
				(copperpour not_allowed)
				(footprints allowed)
			)
			(placement
				(enabled no)
				(sheetname "")
			)
			(fill
				(thermal_gap 0.5)
				(thermal_bridge_width 0.5)
				(island_removal_mode 0)
			)
			(polygon
				(pts
					(xy 27.559 -3.131312) (xy 28.067 -3.131312) (xy 28.067 -3.512312) (xy 27.559 -3.512312)
				)
			)
		)
	)
	(footprint ""
		(layer "F.Cu")
		(at 365.506 -108.614972)
		(property "Reference" "Y7C1"
			(at -1.11633 2.794 90)
			(unlocked yes)
			(layer "F.SilkS")
			(effects
				(font
					(size 0.7874 0.5842)
					(thickness 0.1524)
				)
				(justify left)
			)
		)
		(property "Value" ""
			(at 0 0 0)
			(layer "F.Fab")
			(effects
				(font
					(size 1.27 1.27)
				)
			)
		)
		(duplicate_pad_numbers_are_jumpers no)
		(fp_circle
			(center -1.049782 -0.44323)
			(end -0.922782 -0.44323)
			(stroke
				(width 0.254)
				(type default)
			)
			(fill no)
			(layer "F.SilkS")
		)
		(fp_rect
			(start -0.499872 2.70002)
			(end 2.100072 -0.599948)
			(stroke
				(width 0)
				(type default)
			)
			(fill no)
			(layer "F.CrtYd")
		)
		(fp_line
			(start -0.499872 -0.599948)
			(end 2.100072 -0.599948)
			(stroke
				(width 0.1)
				(type default)
			)
			(layer "F.Fab")
		)
		(fp_line
			(start -0.499872 2.70002)
			(end -0.499872 -0.599948)
			(stroke
				(width 0.1)
				(type default)
			)
			(layer "F.Fab")
		)
		(fp_line
			(start 2.100072 -0.599948)
			(end 2.100072 2.70002)
			(stroke
				(width 0.1)
				(type default)
			)
			(layer "F.Fab")
		)
		(fp_line
			(start 2.100072 2.70002)
			(end -0.499872 2.70002)
			(stroke
				(width 0.1)
				(type default)
			)
			(layer "F.Fab")
		)
		(fp_circle
			(center -1.049782 -0.44323)
			(end -0.922782 -0.44323)
			(stroke
				(width 0.254)
				(type default)
			)
			(fill no)
			(layer "F.Fab")
		)
		(pad "1" smd rect
			(at 0 0)
			(size 1.0414 1.143)
			(layers "F.Cu" "F.Mask" "F.Paste")
			(net "XTAL_PCH_48M_IN")
		)
		(pad "2" smd rect
			(at 0 2.100072)
			(size 1.0414 1.143)
			(layers "F.Cu" "F.Mask" "F.Paste")
			(net "GND")
		)
		(pad "3" smd rect
			(at 1.6002 2.100072)
			(size 1.0414 1.143)
			(layers "F.Cu" "F.Mask" "F.Paste")
			(net "XTAL_PCH_48M_OUT")
		)
		(pad "4" smd rect
			(at 1.6002 0)
			(size 1.0414 1.143)
			(layers "F.Cu" "F.Mask" "F.Paste")
			(net "GND")
		)
	)
	(footprint ""
		(layer "F.Cu")
		(at -0.324612 -117.874034)
		(property "Reference" "R10W6"
			(at -0.8382 -0.67818 0)
			(unlocked yes)
			(layer "F.SilkS")
			(effects
				(font
					(size 0.4064 0.254)
					(thickness 0.1524)
				)
				(justify left)
			)
		)
		(property "Value" ""
			(at 0 0 0)
			(layer "F.Fab")
			(effects
				(font
					(size 1.27 1.27)
				)
			)
		)
		(duplicate_pad_numbers_are_jumpers no)
		(fp_poly
			(pts
				(xy -0.2794 -0.1016) (xy 0.2794 -0.1016) (xy 0.2794 0.9906) (xy -0.2794 0.9906)
			)
			(stroke
				(width 0)
				(type default)
			)
			(fill no)
			(layer "F.CrtYd")
		)
		(fp_line
			(start -0.2794 -0.1016)
			(end -0.2794 0.9906)
			(stroke
				(width 0.1)
				(type default)
			)
			(layer "F.Fab")
		)
		(fp_line
			(start -0.2794 0.9906)
			(end 0.2794 0.9906)
			(stroke
				(width 0.1)
				(type default)
			)
			(layer "F.Fab")
		)
		(fp_line
			(start 0.2794 -0.1016)
			(end -0.2794 -0.1016)
			(stroke
				(width 0.1)
				(type default)
			)
			(layer "F.Fab")
		)
		(fp_line
			(start 0.2794 0.9906)
			(end 0.2794 -0.1016)
			(stroke
				(width 0.1)
				(type default)
			)
			(layer "F.Fab")
		)
		(pad "1" smd rect
			(at 0 0)
			(size 0.508 0.508)
			(layers "F.Cu" "F.Mask" "F.Paste")
			(net "PUMP_TACH1")
		)
		(pad "2" smd rect
			(at 0 0.889)
			(size 0.508 0.508)
			(layers "F.Cu" "F.Mask" "F.Paste")
			(net "PUMP_TACH1_R")
		)
		(zone
			(layer "F.Cu")
			(hatch none 0.5)
			(connect_pads
				(clearance 0)
			)
			(min_thickness 0.25)
			(keepout
				(tracks allowed)
				(vias not_allowed)
				(pads allowed)
				(copperpour not_allowed)
				(footprints allowed)
			)
			(placement
				(enabled no)
				(sheetname "")
			)
			(fill
				(thermal_gap 0.5)
				(thermal_bridge_width 0.5)
				(island_removal_mode 0)
			)
			(polygon
				(pts
					(xy -0.578612 -117.620034) (xy -0.070612 -117.620034) (xy -0.070612 -117.239034) (xy -0.578612 -117.239034)
				)
			)
		)
		(zone
			(layer "F.Cu")
			(hatch none 0.5)
			(connect_pads
				(clearance 0)
			)
			(min_thickness 0.25)
			(keepout
				(tracks not_allowed)
				(vias allowed)
				(pads allowed)
				(copperpour not_allowed)
				(footprints allowed)
			)
			(placement
				(enabled no)
				(sheetname "")
			)
			(fill
				(thermal_gap 0.5)
				(thermal_bridge_width 0.5)
				(island_removal_mode 0)
			)
			(polygon
				(pts
					(xy -0.578612 -117.239034) (xy -0.070612 -117.239034) (xy -0.070612 -117.620034) (xy -0.578612 -117.620034)
				)
			)
		)
	)
	(footprint ""
		(layer "F.Cu")
		(at 490.524546 -153.68016 90)
		(property "Reference" "R9A5"
			(at 0 0 90)
			(layer "F.SilkS")
			(hide yes)
			(effects
				(font
					(size 1.27 1.27)
				)
			)
		)
		(property "Value" ""
			(at 0 0 90)
			(layer "F.Fab")
			(effects
				(font
					(size 1.27 1.27)
				)
			)
		)
		(duplicate_pad_numbers_are_jumpers no)
		(fp_poly
			(pts
				(xy -0.2794 -0.1016) (xy 0.2794 -0.1016) (xy 0.2794 0.9906) (xy -0.2794 0.9906)
			)
			(stroke
				(width 0)
				(type default)
			)
			(fill no)
			(layer "F.CrtYd")
		)
		(fp_line
			(start 0.2794 -0.1016)
			(end -0.2794 -0.1016)
			(stroke
				(width 0.1)
				(type default)
			)
			(layer "F.Fab")
		)
		(fp_line
			(start -0.2794 -0.1016)
			(end -0.2794 0.9906)
			(stroke
				(width 0.1)
				(type default)
			)
			(layer "F.Fab")
		)
		(fp_line
			(start 0.2794 0.9906)
			(end 0.2794 -0.1016)
			(stroke
				(width 0.1)
				(type default)
			)
			(layer "F.Fab")
		)
		(fp_line
			(start -0.2794 0.9906)
			(end 0.2794 0.9906)
			(stroke
				(width 0.1)
				(type default)
			)
			(layer "F.Fab")
		)
		(pad "1" smd rect
			(at 0 0 90)
			(size 0.508 0.508)
			(layers "F.Cu" "F.Mask" "F.Paste")
			(net "P5V_STBY")
		)
		(pad "2" smd rect
			(at 0 0.889 90)
			(size 0.508 0.508)
			(layers "F.Cu" "F.Mask" "F.Paste")
			(net "FM_UART_SWITCH_N")
		)
		(zone
			(layer "F.Cu")
			(hatch none 0.5)
			(connect_pads
				(clearance 0)
			)
			(min_thickness 0.25)
			(keepout
				(tracks allowed)
				(vias not_allowed)
				(pads allowed)
				(copperpour not_allowed)
				(footprints allowed)
			)
			(placement
				(enabled no)
				(sheetname "")
			)
			(fill
				(thermal_gap 0.5)
				(thermal_bridge_width 0.5)
				(island_removal_mode 0)
			)
			(polygon
				(pts
					(xy 490.778546 -153.42616) (xy 490.778546 -153.93416) (xy 491.159546 -153.93416) (xy 491.159546 -153.42616)
				)
			)
		)
		(zone
			(layer "F.Cu")
			(hatch none 0.5)
			(connect_pads
				(clearance 0)
			)
			(min_thickness 0.25)
			(keepout
				(tracks not_allowed)
				(vias allowed)
				(pads allowed)
				(copperpour not_allowed)
				(footprints allowed)
			)
			(placement
				(enabled no)
				(sheetname "")
			)
			(fill
				(thermal_gap 0.5)
				(thermal_bridge_width 0.5)
				(island_removal_mode 0)
			)
			(polygon
				(pts
					(xy 491.159546 -153.42616) (xy 491.159546 -153.93416) (xy 490.778546 -153.93416) (xy 490.778546 -153.42616)
				)
			)
		)
	)
	(footprint ""
		(layer "F.Cu")
		(at -3.175 -135.7122 -90)
		(property "Reference" "R1A3"
			(at 0 0 270)
			(layer "F.SilkS")
			(hide yes)
			(effects
				(font
					(size 1.27 1.27)
				)
			)
		)
		(property "Value" ""
			(at 0 0 270)
			(layer "F.Fab")
			(effects
				(font
					(size 1.27 1.27)
				)
			)
		)
		(duplicate_pad_numbers_are_jumpers no)
		(fp_poly
			(pts
				(xy -0.2794 -0.1016) (xy 0.2794 -0.1016) (xy 0.2794 0.9906) (xy -0.2794 0.9906)
			)
			(stroke
				(width 0)
				(type default)
			)
			(fill no)
			(layer "F.CrtYd")
		)
		(fp_line
			(start -0.2794 0.9906)
			(end 0.2794 0.9906)
			(stroke
				(width 0.1)
				(type default)
			)
			(layer "F.Fab")
		)
		(fp_line
			(start 0.2794 0.9906)
			(end 0.2794 -0.1016)
			(stroke
				(width 0.1)
				(type default)
			)
			(layer "F.Fab")
		)
		(fp_line
			(start -0.2794 -0.1016)
			(end -0.2794 0.9906)
			(stroke
				(width 0.1)
				(type default)
			)
			(layer "F.Fab")
		)
		(fp_line
			(start 0.2794 -0.1016)
			(end -0.2794 -0.1016)
			(stroke
				(width 0.1)
				(type default)
			)
			(layer "F.Fab")
		)
		(pad "1" smd rect
			(at 0 0 270)
			(size 0.508 0.508)
			(layers "F.Cu" "F.Mask" "F.Paste")
			(net "VR_PVDDQ_KLM_PH1_OCSET")
		)
		(pad "2" smd rect
			(at 0 0.889 270)
			(size 0.508 0.508)
			(layers "F.Cu" "F.Mask" "F.Paste")
			(net "GND")
		)
		(zone
			(layer "F.Cu")
			(hatch none 0.5)
			(connect_pads
				(clearance 0)
			)
			(min_thickness 0.25)
			(keepout
				(tracks not_allowed)
				(vias allowed)
				(pads allowed)
				(copperpour not_allowed)
				(footprints allowed)
			)
			(placement
				(enabled no)
				(sheetname "")
			)
			(fill
				(thermal_gap 0.5)
				(thermal_bridge_width 0.5)
				(island_removal_mode 0)
			)
			(polygon
				(pts
					(xy -3.81 -135.9662) (xy -3.81 -135.4582) (xy -3.429 -135.4582) (xy -3.429 -135.9662)
				)
			)
		)
		(zone
			(layer "F.Cu")
			(hatch none 0.5)
			(connect_pads
				(clearance 0)
			)
			(min_thickness 0.25)
			(keepout
				(tracks allowed)
				(vias not_allowed)
				(pads allowed)
				(copperpour not_allowed)
				(footprints allowed)
			)
			(placement
				(enabled no)
				(sheetname "")
			)
			(fill
				(thermal_gap 0.5)
				(thermal_bridge_width 0.5)
				(island_removal_mode 0)
			)
			(polygon
				(pts
					(xy -3.429 -135.9662) (xy -3.429 -135.4582) (xy -3.81 -135.4582) (xy -3.81 -135.9662)
				)
			)
		)
	)
	(footprint ""
		(layer "F.Cu")
		(at 194.804538 -53.48478)
		(property "Reference" "CT1"
			(at -0.762 2.26187 0)
			(unlocked yes)
			(layer "F.SilkS")
			(effects
				(font
					(size 0.7874 0.5842)
					(thickness 0.1524)
				)
				(justify left)
			)
		)
		(property "Value" ""
			(at 0 0 0)
			(layer "F.Fab")
			(effects
				(font
					(size 1.27 1.27)
				)
			)
		)
		(duplicate_pad_numbers_are_jumpers no)
		(fp_poly
			(pts
				(xy 0.3048 -0.1016) (xy 0.3048 0.9906) (xy -0.3048 0.9906) (xy -0.3048 -0.1016)
			)
			(stroke
				(width 0)
				(type default)
			)
			(fill no)
			(layer "F.CrtYd")
		)
		(fp_line
			(start -0.3048 -0.1016)
			(end -0.3048 0.9906)
			(stroke
				(width 0.1)
				(type default)
			)
			(layer "F.Fab")
		)
		(fp_line
			(start -0.3048 0.9906)
			(end 0.3048 0.9906)
			(stroke
				(width 0.1)
				(type default)
			)
			(layer "F.Fab")
		)
		(fp_line
			(start 0.3048 -0.1016)
			(end -0.3048 -0.1016)
			(stroke
				(width 0.1)
				(type default)
			)
			(layer "F.Fab")
		)
		(fp_line
			(start 0.3048 0.9906)
			(end 0.3048 -0.1016)
			(stroke
				(width 0.1)
				(type default)
			)
			(layer "F.Fab")
		)
		(pad "1" smd rect
			(at 0 0)
			(size 0.508 0.508)
			(layers "F.Cu" "F.Mask" "F.Paste")
			(net "VR_PVCCIN_CPU0_AIREF1")
		)
		(pad "2" smd rect
			(at 0 0.889)
			(size 0.508 0.508)
			(layers "F.Cu" "F.Mask" "F.Paste")
			(net "GND")
		)
		(zone
			(layer "F.Cu")
			(hatch none 0.5)
			(connect_pads
				(clearance 0)
			)
			(min_thickness 0.25)
			(keepout
				(tracks allowed)
				(vias not_allowed)
				(pads allowed)
				(copperpour not_allowed)
				(footprints allowed)
			)
			(placement
				(enabled no)
				(sheetname "")
			)
			(fill
				(thermal_gap 0.5)
				(thermal_bridge_width 0.5)
				(island_removal_mode 0)
			)
			(polygon
				(pts
					(xy 194.550538 -53.23078) (xy 195.058538 -53.23078) (xy 195.058538 -52.84978) (xy 194.550538 -52.84978)
				)
			)
		)
		(zone
			(layer "F.Cu")
			(hatch none 0.5)
			(connect_pads
				(clearance 0)
			)
			(min_thickness 0.25)
			(keepout
				(tracks not_allowed)
				(vias allowed)
				(pads allowed)
				(copperpour not_allowed)
				(footprints allowed)
			)
			(placement
				(enabled no)
				(sheetname "")
			)
			(fill
				(thermal_gap 0.5)
				(thermal_bridge_width 0.5)
				(island_removal_mode 0)
			)
			(polygon
				(pts
					(xy 194.550538 -52.84978) (xy 195.058538 -52.84978) (xy 195.058538 -53.23078) (xy 194.550538 -53.23078)
				)
			)
		)
	)
	(footprint ""
		(layer "F.Cu")
		(at 337.947 -17.272 90)
		(property "Reference" "R7G24"
			(at 0 0 90)
			(layer "F.SilkS")
			(hide yes)
			(effects
				(font
					(size 1.27 1.27)
				)
			)
		)
		(property "Value" ""
			(at 0 0 90)
			(layer "F.Fab")
			(effects
				(font
					(size 1.27 1.27)
				)
			)
		)
		(duplicate_pad_numbers_are_jumpers no)
		(fp_rect
			(start -0.2794 -0.1016)
			(end 0.2794 0.9906)
			(stroke
				(width 0)
				(type default)
			)
			(fill no)
			(layer "F.CrtYd")
		)
		(fp_line
			(start 0.2794 -0.1016)
			(end -0.2794 -0.1016)
			(stroke
				(width 0.1)
				(type default)
			)
			(layer "F.Fab")
		)
		(fp_line
			(start -0.2794 -0.1016)
			(end -0.2794 0.9906)
			(stroke
				(width 0.1)
				(type default)
			)
			(layer "F.Fab")
		)
		(fp_line
			(start 0.2794 0.9906)
			(end 0.2794 -0.1016)
			(stroke
				(width 0.1)
				(type default)
			)
			(layer "F.Fab")
		)
		(fp_line
			(start -0.2794 0.9906)
			(end 0.2794 0.9906)
			(stroke
				(width 0.1)
				(type default)
			)
			(layer "F.Fab")
		)
		(pad "1" smd rect
			(at 0 0 90)
			(size 0.508 0.508)
			(layers "F.Cu" "F.Mask" "F.Paste")
			(net "SVID_CLK1_CPU0_R")
		)
		(pad "2" smd rect
			(at 0 0.889 90)
			(size 0.508 0.508)
			(layers "F.Cu" "F.Mask" "F.Paste")
			(net "SVID_CLK_PVDDQ_ABC")
		)
		(zone
			(layer "F.Cu")
			(hatch none 0.5)
			(connect_pads
				(clearance 0)
			)
			(min_thickness 0.25)
			(keepout
				(tracks not_allowed)
				(vias allowed)
				(pads allowed)
				(copperpour not_allowed)
				(footprints allowed)
			)
			(placement
				(enabled no)
				(sheetname "")
			)
			(fill
				(thermal_gap 0.5)
				(thermal_bridge_width 0.5)
				(island_removal_mode 0)
			)
			(polygon
				(pts
					(xy 338.201 -17.018) (xy 338.582 -17.018) (xy 338.582 -17.526) (xy 338.201 -17.526)
				)
			)
		)
		(zone
			(layer "F.Cu")
			(hatch none 0.5)
			(connect_pads
				(clearance 0)
			)
			(min_thickness 0.25)
			(keepout
				(tracks allowed)
				(vias not_allowed)
				(pads allowed)
				(copperpour not_allowed)
				(footprints allowed)
			)
			(placement
				(enabled no)
				(sheetname "")
			)
			(fill
				(thermal_gap 0.5)
				(thermal_bridge_width 0.5)
				(island_removal_mode 0)
			)
			(polygon
				(pts
					(xy 338.201 -17.018) (xy 338.582 -17.018) (xy 338.582 -17.526) (xy 338.201 -17.526)
				)
			)
		)
	)
)
